(kicad_pcb
	(version 20260206)
	(generator "pcbnew")
	(generator_version "10.0")
	(general
		(thickness 1.6)
		(legacy_teardrops no)
	)
	(paper "A4")
	(title_block
		(title "Bryce Canyon_R.DPB_16317-1_OCP.brd")
		(comment 1 "Bryce Canyon / footprints 1924-1926 of 2099")
	)
	(layers
		(0 "F.Cu" signal "TOP")
		(4 "In1.Cu" signal "L2GND")
		(6 "In2.Cu" signal "L3")
		(8 "In3.Cu" signal "L4VCC")
		(10 "In4.Cu" signal "L5VCC")
		(12 "In5.Cu" signal "L6")
		(14 "In6.Cu" signal "L7GND")
		(2 "B.Cu" signal "BOTTOM")
		(9 "F.Adhes" user "F.Adhesive")
		(11 "B.Adhes" user "B.Adhesive")
		(13 "F.Paste" user "Package Geometry/Pastemask Top")
		(15 "B.Paste" user "Package Geometry/Pastemask Bottom")
		(5 "F.SilkS" user "Ref Des/Silkscreen Top")
		(7 "B.SilkS" user "Ref Des/Silkscreen Bottom")
		(1 "F.Mask" user "Board Geometry/Soldermask Top")
		(3 "B.Mask" user "Board Geometry/Soldermask Bottom")
		(17 "Dwgs.User" user "User.Drawings")
		(19 "Cmts.User" user "User.Comments")
		(21 "Eco1.User" user "User.Eco1")
		(23 "Eco2.User" user "User.Eco2")
		(25 "Edge.Cuts" user "Board Geometry/Outline")
		(27 "Margin" user)
		(31 "F.CrtYd" user "Package Geometry/Place Bound Top")
		(29 "B.CrtYd" user "Package Geometry/Place Bound Bottom")
		(35 "F.Fab" user "Ref Des/Assembly Top")
		(33 "B.Fab" user "Ref Des/Assembly Bottom")
	)
	(footprint ""
		(layer "F.Cu")
		(at 420.200074 -28.910026 -90)
		(property "Reference" "HDDSAS33"
			(at 0 0 270)
			(layer "F.SilkS")
			(hide yes)
			(effects
				(font
					(size 1.27 1.27)
				)
			)
		)
		(property "Value" "SKT-SAS15P-14P-45-GP"
			(at -20.7645 -8.9789 270)
			(unlocked yes)
			(layer "F.Fab")
			(hide yes)
			(effects
				(font
					(size 1.016 1.016)
					(thickness 0.1524)
				)
			)
		)
		(property "Device Type" "10120818-001C-TRLF"
			(at -20.7645 -10.5029 270)
			(unlocked yes)
			(layer "F.Fab")
			(hide yes)
			(effects
				(font
					(size 1.016 1.016)
					(thickness 0.1524)
				)
			)
		)
		(duplicate_pad_numbers_are_jumpers no)
		(fp_line
			(start 1.651 4.2926)
			(end 1.651 3.0099)
			(stroke
				(width 0.1524)
				(type default)
			)
			(layer "F.SilkS")
		)
		(fp_line
			(start 8.509 4.2926)
			(end 1.651 4.2926)
			(stroke
				(width 0.1524)
				(type default)
			)
			(layer "F.SilkS")
		)
		(fp_line
			(start -23.4188 3.0099)
			(end -23.4188 -3.2512)
			(stroke
				(width 0.1524)
				(type default)
			)
			(layer "F.SilkS")
		)
		(fp_line
			(start 1.651 3.0099)
			(end -23.4188 3.0099)
			(stroke
				(width 0.1524)
				(type default)
			)
			(layer "F.SilkS")
		)
		(fp_line
			(start 8.509 3.0099)
			(end 8.509 4.2926)
			(stroke
				(width 0.1524)
				(type default)
			)
			(layer "F.SilkS")
		)
		(fp_line
			(start 23.4188 3.0099)
			(end 8.509 3.0099)
			(stroke
				(width 0.1524)
				(type default)
			)
			(layer "F.SilkS")
		)
		(fp_line
			(start -23.4188 -3.2512)
			(end 23.4188 -3.2512)
			(stroke
				(width 0.1524)
				(type default)
			)
			(layer "F.SilkS")
		)
		(fp_line
			(start 23.4188 -3.2512)
			(end 23.4188 3.0099)
			(stroke
				(width 0.1524)
				(type default)
			)
			(layer "F.SilkS")
		)
		(fp_line
			(start 15.5067 -3.3401)
			(end 16.2687 -3.3401)
			(stroke
				(width 0.3302)
				(type default)
			)
			(layer "F.SilkS")
		)
		(fp_poly
			(pts
				(xy 15.868904 -3.230372) (xy 16.503904 -3.865372) (xy 15.233904 -3.865372)
			)
			(stroke
				(width 0)
				(type default)
			)
			(fill yes)
			(layer "F.SilkS")
		)
		(fp_poly
			(pts
				(xy -22.8727 -2.7559) (xy 22.8727 -2.7559) (xy 22.8727 2.7559) (xy 8.255 2.7559) (xy 8.255 3.5179)
				(xy 1.905 3.5179) (xy 1.905 2.7559) (xy -22.8727 2.7559)
			)
			(stroke
				(width 0)
				(type default)
			)
			(fill no)
			(layer "F.CrtYd")
		)
		(fp_poly
			(pts
				(xy 1.397 4.5466) (xy 1.397 3.2639) (xy -23.6728 3.2639) (xy -23.6728 -3.5052) (xy 23.6728 -3.5052)
				(xy 23.6728 -0.00635) (xy 22.8727 -0.00635) (xy 22.8727 -2.7559) (xy -22.8727 -2.7559) (xy -22.8727 2.7559)
				(xy 1.905 2.7559) (xy 1.905 3.5179) (xy 8.255 3.5179) (xy 8.255 2.7559) (xy 22.8727 2.7559) (xy 22.8727 0.00635)
				(xy 23.6728 0.00635) (xy 23.6728 3.2639) (xy 8.763 3.2639) (xy 8.763 4.5466)
			)
			(stroke
				(width 0)
				(type default)
			)
			(fill no)
			(layer "F.CrtYd")
		)
		(fp_poly
			(pts
				(xy 1.397 4.5466) (xy 1.397 3.2639) (xy -23.6728 3.2639) (xy -23.6728 -3.5052) (xy 23.6728 -3.5052)
				(xy 23.6728 3.2639) (xy 8.763 3.2639) (xy 8.763 4.5466)
			)
			(stroke
				(width 0)
				(type default)
			)
			(fill no)
			(layer "F.Fab")
		)
		(pad "" np_thru_hole circle
			(at -18.874994 0 270)
			(size 0.254 0.254)
			(drill 1.3462)
			(layers "*.Cu" "*.Mask")
			(clearance 0.9017)
			(thermal_gap 0.9017)
		)
		(pad "" np_thru_hole circle
			(at 18.874994 0 270)
			(size 0.254 0.254)
			(drill 0.9398)
			(layers "*.Cu" "*.Mask")
			(clearance 0.6985)
			(thermal_gap 0.6985)
		)
		(pad "G1" smd rect
			(at 21.874988 0 270)
			(size 2.5908 2.5908)
			(layers "F.Cu" "F.Mask" "F.Paste")
			(net "GND")
		)
		(pad "G2" smd rect
			(at -21.874988 0 270)
			(size 2.5908 2.5908)
			(layers "F.Cu" "F.Mask" "F.Paste")
			(net "GND")
		)
		(pad "P1" smd rect
			(at 1.905 -1.82499 270)
			(size 0.6096 2.3622)
			(layers "F.Cu" "F.Mask" "F.Paste")
			(net "Net_1629")
		)
		(pad "P2" smd rect
			(at 0.635 -1.82499 270)
			(size 0.6096 2.3622)
			(layers "F.Cu" "F.Mask" "F.Paste")
			(net "Net_1630")
		)
		(pad "P3" smd rect
			(at -0.635 -1.82499 270)
			(size 0.6096 2.3622)
			(layers "F.Cu" "F.Mask" "F.Paste")
			(net "Net_1631")
		)
		(pad "P4" smd rect
			(at -1.905 -1.82499 270)
			(size 0.6096 2.3622)
			(layers "F.Cu" "F.Mask" "F.Paste")
			(net "GND")
		)
		(pad "P5" smd rect
			(at -3.175 -1.82499 270)
			(size 0.6096 2.3622)
			(layers "F.Cu" "F.Mask" "F.Paste")
			(net "HDD_PRSNT_33")
		)
		(pad "P6" smd rect
			(at -4.445 -1.82499 270)
			(size 0.6096 2.3622)
			(layers "F.Cu" "F.Mask" "F.Paste")
			(net "GND")
		)
		(pad "P7" smd rect
			(at -5.715 -1.82499 270)
			(size 0.6096 2.3622)
			(layers "F.Cu" "F.Mask" "F.Paste")
			(net "5V_PRE_33")
		)
		(pad "P8" smd rect
			(at -6.985 -1.82499 270)
			(size 0.6096 2.3622)
			(layers "F.Cu" "F.Mask" "F.Paste")
			(net "P5V_HDD33")
		)
		(pad "P9" smd rect
			(at -8.255 -1.82499 270)
			(size 0.6096 2.3622)
			(layers "F.Cu" "F.Mask" "F.Paste")
			(net "P5V_HDD33")
		)
		(pad "P10" smd rect
			(at -9.525 -1.82499 270)
			(size 0.6096 2.3622)
			(layers "F.Cu" "F.Mask" "F.Paste")
			(net "GND")
		)
		(pad "P11" smd rect
			(at -10.795 -1.82499 270)
			(size 0.6096 2.3622)
			(layers "F.Cu" "F.Mask" "F.Paste")
			(net "ACT_HDD_33")
		)
		(pad "P12" smd rect
			(at -12.065 -1.82499 270)
			(size 0.6096 2.3622)
			(layers "F.Cu" "F.Mask" "F.Paste")
			(net "GND")
		)
		(pad "P13" smd rect
			(at -13.335 -1.82499 270)
			(size 0.6096 2.3622)
			(layers "F.Cu" "F.Mask" "F.Paste")
			(net "12V_PRE_33")
		)
		(pad "P14" smd rect
			(at -14.605 -1.82499 270)
			(size 0.6096 2.3622)
			(layers "F.Cu" "F.Mask" "F.Paste")
			(net "P12V_HDD33")
		)
		(pad "P15" smd rect
			(at -15.875 -1.82499 270)
			(size 0.6096 2.3622)
			(layers "F.Cu" "F.Mask" "F.Paste")
			(net "P12V_HDD33")
		)
		(pad "S1" smd rect
			(at 15.875 -1.82499 270)
			(size 0.6096 2.3622)
			(layers "F.Cu" "F.Mask" "F.Paste")
			(net "GND")
		)
		(pad "S2" smd rect
			(at 14.605 -1.82499 270)
			(size 0.6096 2.3622)
			(layers "F.Cu" "F.Mask" "F.Paste")
			(net "SAS_HDD_RX_P33")
		)
		(pad "S3" smd rect
			(at 13.335 -1.82499 270)
			(size 0.6096 2.3622)
			(layers "F.Cu" "F.Mask" "F.Paste")
			(net "SAS_HDD_RX_N33")
		)
		(pad "S4" smd rect
			(at 12.065 -1.82499 270)
			(size 0.6096 2.3622)
			(layers "F.Cu" "F.Mask" "F.Paste")
			(net "GND")
		)
		(pad "S5" smd rect
			(at 10.795 -1.82499 270)
			(size 0.6096 2.3622)
			(layers "F.Cu" "F.Mask" "F.Paste")
			(net "PHY_DRV_B_TO_SCC_B_33_DN")
		)
		(pad "S6" smd rect
			(at 9.525 -1.82499 270)
			(size 0.6096 2.3622)
			(layers "F.Cu" "F.Mask" "F.Paste")
			(net "PHY_DRV_B_TO_SCC_B_33_DP")
		)
		(pad "S7" smd rect
			(at 8.255 -1.82499 270)
			(size 0.6096 2.3622)
			(layers "F.Cu" "F.Mask" "F.Paste")
			(net "GND")
		)
		(pad "S8" smd rect
			(at 7.480046 2.845054 270)
			(size 0.508 2.3622)
			(layers "F.Cu" "F.Mask" "F.Paste")
			(net "GND")
		)
		(pad "S9" smd rect
			(at 6.679946 2.845054 270)
			(size 0.508 2.3622)
			(layers "F.Cu" "F.Mask" "F.Paste")
			(net "Net_458")
		)
		(pad "S10" smd rect
			(at 5.8801 2.845054 270)
			(size 0.508 2.3622)
			(layers "F.Cu" "F.Mask" "F.Paste")
			(net "Net_350")
		)
		(pad "S11" smd rect
			(at 5.08 2.845054 270)
			(size 0.508 2.3622)
			(layers "F.Cu" "F.Mask" "F.Paste")
			(net "GND")
		)
		(pad "S12" smd rect
			(at 4.2799 2.845054 270)
			(size 0.508 2.3622)
			(layers "F.Cu" "F.Mask" "F.Paste")
			(net "Net_386")
		)
		(pad "S13" smd rect
			(at 3.480054 2.845054 270)
			(size 0.508 2.3622)
			(layers "F.Cu" "F.Mask" "F.Paste")
			(net "Net_422")
		)
		(pad "S14" smd rect
			(at 2.679954 2.845054 270)
			(size 0.508 2.3622)
			(layers "F.Cu" "F.Mask" "F.Paste")
			(net "GND")
		)
		(zone
			(layer "F.Cu")
			(hatch none 0.5)
			(connect_pads
				(clearance 0)
			)
			(min_thickness 0.25)
			(keepout
				(tracks not_allowed)
				(vias allowed)
				(pads allowed)
				(copperpour not_allowed)
				(footprints allowed)
			)
			(placement
				(enabled no)
				(sheetname "")
			)
			(fill
				(thermal_gap 0.5)
				(thermal_bridge_width 0.5)
				(island_removal_mode 0)
			)
			(polygon
				(pts
					(xy 423.857674 -45.648626) (xy 416.783774 -45.648626) (xy 416.783774 -52.582826) (xy 417.888674 -52.582826)
					(xy 417.888674 -48.468026) (xy 422.511474 -48.468026) (xy 422.511474 -52.582826) (xy 423.857674 -52.582826)
				)
			)
		)
		(zone
			(layer "F.Cu")
			(hatch none 0.5)
			(connect_pads
				(clearance 0)
			)
			(min_thickness 0.25)
			(keepout
				(tracks allowed)
				(vias not_allowed)
				(pads allowed)
				(copperpour not_allowed)
				(footprints allowed)
			)
			(placement
				(enabled no)
				(sheetname "")
			)
			(fill
				(thermal_gap 0.5)
				(thermal_bridge_width 0.5)
				(island_removal_mode 0)
			)
			(polygon
				(pts
					(xy 423.857674 -45.648626) (xy 416.783774 -45.648626) (xy 416.783774 -52.582826) (xy 417.888674 -52.582826)
					(xy 417.888674 -48.468026) (xy 422.511474 -48.468026) (xy 422.511474 -52.582826) (xy 423.857674 -52.582826)
				)
			)
		)
		(zone
			(layer "F.Cu")
			(hatch none 0.5)
			(connect_pads
				(clearance 0)
			)
			(min_thickness 0.25)
			(keepout
				(tracks not_allowed)
				(vias allowed)
				(pads allowed)
				(copperpour not_allowed)
				(footprints allowed)
			)
			(placement
				(enabled no)
				(sheetname "")
			)
			(fill
				(thermal_gap 0.5)
				(thermal_bridge_width 0.5)
				(island_removal_mode 0)
			)
			(polygon
				(pts
					(xy 423.857674 -12.171426) (xy 416.783774 -12.171426) (xy 416.783774 -5.237226) (xy 417.888674 -5.237226)
					(xy 417.888674 -9.352026) (xy 422.511474 -9.352026) (xy 422.511474 -5.237226) (xy 423.857674 -5.237226)
				)
			)
		)
		(zone
			(layer "F.Cu")
			(hatch none 0.5)
			(connect_pads
				(clearance 0)
			)
			(min_thickness 0.25)
			(keepout
				(tracks allowed)
				(vias not_allowed)
				(pads allowed)
				(copperpour not_allowed)
				(footprints allowed)
			)
			(placement
				(enabled no)
				(sheetname "")
			)
			(fill
				(thermal_gap 0.5)
				(thermal_bridge_width 0.5)
				(island_removal_mode 0)
			)
			(polygon
				(pts
					(xy 423.857674 -12.171426) (xy 416.783774 -12.171426) (xy 416.783774 -5.237226) (xy 417.888674 -5.237226)
					(xy 417.888674 -9.352026) (xy 422.511474 -9.352026) (xy 422.511474 -5.237226) (xy 423.857674 -5.237226)
				)
			)
		)
		(zone
			(layers "F.Cu" "B.Cu" "In1.Cu" "In2.Cu" "In3.Cu" "In4.Cu" "In5.Cu" "In6.Cu")
			(hatch none 0.5)
			(connect_pads
				(clearance 0)
			)
			(min_thickness 0.25)
			(keepout
				(tracks not_allowed)
				(vias allowed)
				(pads allowed)
				(copperpour not_allowed)
				(footprints allowed)
			)
			(placement
				(enabled no)
				(sheetname "")
			)
			(fill
				(thermal_gap 0.5)
				(thermal_bridge_width 0.5)
				(island_removal_mode 0)
			)
			(polygon
				(pts
					(arc
						(start 420.974774 -10.035032)
						(mid 419.425374 -10.035032)
						(end 420.974774 -10.035032)
					)
				)
			)
		)
		(zone
			(layers "F.Cu" "B.Cu" "In1.Cu" "In2.Cu" "In3.Cu" "In4.Cu" "In5.Cu" "In6.Cu")
			(hatch none 0.5)
			(connect_pads
				(clearance 0)
			)
			(min_thickness 0.25)
			(keepout
				(tracks not_allowed)
				(vias allowed)
				(pads allowed)
				(copperpour not_allowed)
				(footprints allowed)
			)
			(placement
				(enabled no)
				(sheetname "")
			)
			(fill
				(thermal_gap 0.5)
				(thermal_bridge_width 0.5)
				(island_removal_mode 0)
			)
			(polygon
				(pts
					(arc
						(start 421.177974 -47.78502)
						(mid 419.222174 -47.78502)
						(end 421.177974 -47.78502)
					)
				)
			)
		)
	)
	(footprint ""
		(layer "F.Cu")
		(at 77.978 -16.637 90)
		(property "Reference" "R682"
			(at 0 0 90)
			(layer "F.SilkS")
			(hide yes)
			(effects
				(font
					(size 1.27 1.27)
				)
			)
		)
		(property "Value" "4K7R2J-2-GP"
			(at 0.064008 -3.993896 90)
			(unlocked yes)
			(layer "F.Fab")
			(hide yes)
			(effects
				(font
					(size 1.016 1.016)
					(thickness 0.1524)
				)
			)
		)
		(property "Device Type" "R402H16"
			(at 0.064008 -5.517896 90)
			(unlocked yes)
			(layer "F.Fab")
			(hide yes)
			(effects
				(font
					(size 1.016 1.016)
					(thickness 0.1524)
				)
			)
		)
		(duplicate_pad_numbers_are_jumpers no)
		(fp_line
			(start 0.508 -0.9398)
			(end -0.508 -0.9398)
			(stroke
				(width 0.1524)
				(type default)
			)
			(layer "F.SilkS")
		)
		(fp_line
			(start -0.508 -0.9398)
			(end -0.508 0.9398)
			(stroke
				(width 0.1524)
				(type default)
			)
			(layer "F.SilkS")
		)
		(fp_rect
			(start -0.508 0.9398)
			(end 0.508 -0.9398)
			(stroke
				(width 0)
				(type default)
			)
			(fill no)
			(layer "F.CrtYd")
		)
		(fp_rect
			(start -0.508 0.9398)
			(end 0.508 -0.9398)
			(stroke
				(width 0)
				(type default)
			)
			(fill no)
			(layer "F.Fab")
		)
		(pad "1" smd custom
			(at 0 -0.4445 90)
			(size 0.1397 0.1397)
			(layers "F.Cu" "F.Mask" "F.Paste")
			(net "P12V_B")
			(options
				(clearance outline)
				(anchor circle)
			)
			(primitives
				(gr_poly
					(pts
						(arc
							(start -0.1778 -0.2794)
							(mid -0.249642 -0.249642)
							(end -0.2794 -0.1778)
						)
						(arc
							(start -0.2794 0.1778)
							(mid -0.249642 0.249642)
							(end -0.1778 0.2794)
						)
						(arc
							(start 0.1778 0.2794)
							(mid 0.249642 0.249642)
							(end 0.2794 0.1778)
						)
						(arc
							(start 0.2794 -0.1778)
							(mid 0.249642 -0.249642)
							(end 0.1778 -0.2794)
						)
					)
					(width 0)
					(fill yes)
				)
			)
		)
		(pad "2" smd custom
			(at 0 0.4445 90)
			(size 0.1397 0.1397)
			(layers "F.Cu" "F.Mask" "F.Paste")
			(net "SW_HDD_R26")
			(options
				(clearance outline)
				(anchor circle)
			)
			(primitives
				(gr_poly
					(pts
						(arc
							(start -0.1778 -0.2794)
							(mid -0.249642 -0.249642)
							(end -0.2794 -0.1778)
						)
						(arc
							(start -0.2794 0.1778)
							(mid -0.249642 0.249642)
							(end -0.1778 0.2794)
						)
						(arc
							(start 0.1778 0.2794)
							(mid 0.249642 0.249642)
							(end 0.2794 0.1778)
						)
						(arc
							(start 0.2794 -0.1778)
							(mid 0.249642 -0.249642)
							(end 0.1778 -0.2794)
						)
					)
					(width 0)
					(fill yes)
				)
			)
		)
	)
	(footprint ""
		(layer "F.Cu")
		(at 393.674854 -293.799768)
		(property "Reference" ""
			(at 0 0 0)
			(layer "F.SilkS")
			(hide yes)
			(effects
				(font
					(size 1.27 1.27)
				)
			)
		)
		(property "Value" "*"
			(at -8.398764 -8.057642 0)
			(unlocked yes)
			(layer "F.Fab")
			(hide yes)
			(effects
				(font
					(size 1.016 1.016)
					(thickness 0.1524)
				)
			)
		)
		(duplicate_pad_numbers_are_jumpers no)
		(fp_poly
			(pts
				(arc
					(start 7.3152 0)
					(mid 0 7.3152)
					(end -7.3152 0)
				)
				(arc
					(start -7.3152 -5.9944)
					(mid 0 -13.3096)
					(end 7.3152 -5.9944)
				)
			)
			(stroke
				(width 0)
				(type default)
			)
			(fill no)
			(layer "B.CrtYd")
		)
		(fp_poly
			(pts
				(arc
					(start 7.3152 0)
					(mid 0 7.3152)
					(end -7.3152 0)
				)
				(arc
					(start -7.3152 -5.9944)
					(mid 0 -13.3096)
					(end 7.3152 -5.9944)
				)
			)
			(stroke
				(width 0)
				(type default)
			)
			(fill no)
			(layer "F.CrtYd")
		)
		(fp_poly
			(pts
				(arc
					(start 7.3152 0)
					(mid 0 7.3152)
					(end -7.3152 0)
				)
				(arc
					(start -7.3152 -5.9944)
					(mid 0 -13.3096)
					(end 7.3152 -5.9944)
				)
			)
			(stroke
				(width 0)
				(type default)
			)
			(fill no)
			(layer "B.Fab")
		)
		(fp_poly
			(pts
				(arc
					(start 7.3152 0)
					(mid 0 7.3152)
					(end -7.3152 0)
				)
				(arc
					(start -7.3152 -5.9944)
					(mid 0 -13.3096)
					(end 7.3152 -5.9944)
				)
			)
			(stroke
				(width 0)
				(type default)
			)
			(fill no)
			(layer "F.Fab")
		)
		(pad "1" thru_hole oval
			(at 0 0)
			(size 14.0208 20.0152)
			(drill 0.0254
				(offset 0 -2.9972)
			)
			(layers "*.Cu" "*.Mask")
			(remove_unused_layers no)
			(net "Net_41")
			(clearance -1.002284)
			(thermal_gap 0.1524)
			(padstack
				(mode front_inner_back)
				(layer "Inner"
					(shape custom)
					(size 2.928012 2.928012)
					(options
						(anchor circle)
					)
					(primitives
						(gr_poly
							(pts
								(arc
									(start 4.571746 -2.084324)
									(mid 0.000333 7.430372)
									(end -4.571492 -2.084324)
								)
								(arc
									(start -4.571492 -2.084324)
									(mid -3.570296 -3.611977)
									(end -2.875026 -5.30098)
								)
								(arc
									(start -2.875026 -5.30098)
									(mid 0.000217 -7.43089)
									(end 2.87528 -5.30098)
								)
								(arc
									(start 2.87528 -5.30098)
									(mid 3.570511 -3.611956)
									(end 4.571746 -2.084324)
								)
							)
							(width 0)
							(fill yes)
						)
					)
					(clearance 0.1524)
				)
				(layer "B.Cu"
					(shape oval)
					(size 14.0208 20.0152)
					(offset 0 -2.9972)
					(clearance -1.002284)
				)
			)
		)
		(zone
			(layers "F.Cu" "B.Cu" "In1.Cu" "In2.Cu" "In3.Cu" "In4.Cu" "In5.Cu" "In6.Cu")
			(hatch none 0.5)
			(connect_pads
				(clearance 0)
			)
			(min_thickness 0.25)
			(keepout
				(tracks not_allowed)
				(vias allowed)
				(pads allowed)
				(copperpour not_allowed)
				(footprints allowed)
			)
			(placement
				(enabled no)
				(sheetname "")
			)
			(fill
				(thermal_gap 0.5)
				(thermal_bridge_width 0.5)
				(island_removal_mode 0)
			)
			(polygon
				(pts
					(arc
						(start 386.664454 -299.794168)
						(mid 393.674854 -306.804568)
						(end 400.685254 -299.794168)
					)
					(arc
						(start 400.685254 -293.799768)
						(mid 393.674854 -286.789368)
						(end 386.664454 -293.799768)
					)
				)
			)
		)
	)
)
